(kicad_pcb
	(version 20260206)
	(generator "pcbnew")
	(generator_version "10.0")
	(general
		(thickness 1.6)
		(legacy_teardrops no)
	)
	(paper "A4")
	(title_block
		(title "01162023_DA0F0TEBIF0_F0T_Expander_BD_F_brd_V02_OCP.brd")
		(comment 1 "Grand Teton / footprints 8561-8567 of 9728")
	)
	(layers
		(0 "F.Cu" signal "TOP")
		(4 "In1.Cu" signal "GND")
		(6 "In2.Cu" signal "VCC")
		(8 "In3.Cu" signal "VCC1")
		(10 "In4.Cu" signal "GND1")
		(12 "In5.Cu" signal "IN1")
		(14 "In6.Cu" signal "GND2")
		(16 "In7.Cu" signal "IN2")
		(18 "In8.Cu" signal "GND3")
		(20 "In9.Cu" signal "IN3")
		(22 "In10.Cu" signal "GND4")
		(24 "In11.Cu" signal "IN4")
		(26 "In12.Cu" signal "GND5")
		(28 "In13.Cu" signal "IN5")
		(30 "In14.Cu" signal "GND6")
		(32 "In15.Cu" signal "IN6")
		(34 "In16.Cu" signal "GND7")
		(2 "B.Cu" signal "BOTTOM")
		(9 "F.Adhes" user "F.Adhesive")
		(11 "B.Adhes" user "B.Adhesive")
		(13 "F.Paste" user "Package Geometry/Pastemask Top")
		(15 "B.Paste" user "Package Geometry/Pastemask Bottom")
		(5 "F.SilkS" user "Ref Des/Silkscreen Top")
		(7 "B.SilkS" user "Ref Des/Silkscreen Bottom")
		(1 "F.Mask" user "Board Geometry/Soldermask Top")
		(3 "B.Mask" user "Board Geometry/Soldermask Bottom")
		(17 "Dwgs.User" user "User.Drawings")
		(19 "Cmts.User" user "User.Comments")
		(21 "Eco1.User" user "User.Eco1")
		(23 "Eco2.User" user "User.Eco2")
		(25 "Edge.Cuts" user "Board Geometry/Outline")
		(27 "Margin" user)
		(31 "F.CrtYd" user "Package Geometry/Place Bound Top")
		(29 "B.CrtYd" user "Package Geometry/Place Bound Bottom")
		(35 "F.Fab" user "Ref Des/Assembly Top")
		(33 "B.Fab" user "Ref Des/Assembly Bottom")
	)
	(footprint ""
		(layer "B.Cu")
		(at 247.099582 -229.997)
		(property "Reference" "R3482"
			(at 0 0 0)
			(layer "B.SilkS")
			(hide yes)
			(effects
				(font
					(size 1.27 1.27)
				)
				(justify mirror)
			)
		)
		(property "Value" ""
			(at 0 0 0)
			(layer "B.Fab")
			(effects
				(font
					(size 1.27 1.27)
				)
				(justify mirror)
			)
		)
		(duplicate_pad_numbers_are_jumpers no)
		(fp_line
			(start -0.7874 -0.4064)
			(end -0.7874 0.4064)
			(stroke
				(width 0.1524)
				(type default)
			)
			(layer "B.SilkS")
		)
		(fp_line
			(start -0.7874 0.4064)
			(end 0.7874 0.4064)
			(stroke
				(width 0.1524)
				(type default)
			)
			(layer "B.SilkS")
		)
		(fp_line
			(start 0.7874 -0.4064)
			(end -0.7874 -0.4064)
			(stroke
				(width 0.1524)
				(type default)
			)
			(layer "B.SilkS")
		)
		(fp_line
			(start 0.7874 0.4064)
			(end 0.7874 -0.4064)
			(stroke
				(width 0.1524)
				(type default)
			)
			(layer "B.SilkS")
		)
		(fp_line
			(start -0.67945 -0.3048)
			(end -0.67945 0.3048)
			(stroke
				(width 0.1)
				(type default)
			)
			(layer "B.Fab")
		)
		(fp_line
			(start -0.67945 0.3048)
			(end -0.120396 0.3048)
			(stroke
				(width 0.1)
				(type default)
			)
			(layer "B.Fab")
		)
		(fp_line
			(start -0.12065 -0.3048)
			(end -0.67945 -0.3048)
			(stroke
				(width 0.1)
				(type default)
			)
			(layer "B.Fab")
		)
		(fp_line
			(start -0.12065 -0.2794)
			(end -0.12065 -0.3048)
			(stroke
				(width 0.1)
				(type default)
			)
			(layer "B.Fab")
		)
		(fp_line
			(start -0.120396 0.2794)
			(end 0.12065 0.2794)
			(stroke
				(width 0.1)
				(type default)
			)
			(layer "B.Fab")
		)
		(fp_line
			(start -0.120396 0.3048)
			(end -0.120396 0.2794)
			(stroke
				(width 0.1)
				(type default)
			)
			(layer "B.Fab")
		)
		(fp_line
			(start 0.12065 -0.305054)
			(end 0.12065 -0.2794)
			(stroke
				(width 0.1)
				(type default)
			)
			(layer "B.Fab")
		)
		(fp_line
			(start 0.12065 -0.2794)
			(end -0.12065 -0.2794)
			(stroke
				(width 0.1)
				(type default)
			)
			(layer "B.Fab")
		)
		(fp_line
			(start 0.12065 0.2794)
			(end 0.12065 0.3048)
			(stroke
				(width 0.1)
				(type default)
			)
			(layer "B.Fab")
		)
		(fp_line
			(start 0.12065 0.3048)
			(end 0.67945 0.3048)
			(stroke
				(width 0.1)
				(type default)
			)
			(layer "B.Fab")
		)
		(fp_line
			(start 0.67945 -0.305054)
			(end 0.12065 -0.305054)
			(stroke
				(width 0.1)
				(type default)
			)
			(layer "B.Fab")
		)
		(fp_line
			(start 0.67945 0.3048)
			(end 0.67945 -0.305054)
			(stroke
				(width 0.1)
				(type default)
			)
			(layer "B.Fab")
		)
		(pad "1" smd circle
			(at 0.40005 0 180)
			(size 0 0)
			(layers "B.Cu" "B.Mask" "B.Paste")
			(net "SPI_PEX2_SDIO2_R")
		)
		(pad "2" smd circle
			(at -0.40005 0 180)
			(size 0 0)
			(layers "B.Cu" "B.Mask" "B.Paste")
			(net "SPI_PEX2_SDIO2_R1")
		)
	)
	(footprint ""
		(layer "B.Cu")
		(at 237.59922 -278.89708 -90)
		(property "Reference" "C4344"
			(at 0 0 90)
			(layer "B.SilkS")
			(hide yes)
			(effects
				(font
					(size 1.27 1.27)
				)
				(justify mirror)
			)
		)
		(property "Value" ""
			(at 0 0 90)
			(layer "B.Fab")
			(effects
				(font
					(size 1.27 1.27)
				)
				(justify mirror)
			)
		)
		(duplicate_pad_numbers_are_jumpers no)
		(fp_line
			(start -1.2954 0.5842)
			(end 1.2954 0.5842)
			(stroke
				(width 0.1524)
				(type default)
			)
			(layer "B.SilkS")
		)
		(fp_line
			(start 1.2954 0.5842)
			(end 1.2954 -0.5842)
			(stroke
				(width 0.1524)
				(type default)
			)
			(layer "B.SilkS")
		)
		(fp_line
			(start -1.2954 -0.5842)
			(end -1.2954 0.5842)
			(stroke
				(width 0.1524)
				(type default)
			)
			(layer "B.SilkS")
		)
		(fp_line
			(start 1.2954 -0.5842)
			(end -1.2954 -0.5842)
			(stroke
				(width 0.1524)
				(type default)
			)
			(layer "B.SilkS")
		)
		(fp_line
			(start -0.8636 0.4572)
			(end 0.8636 0.4572)
			(stroke
				(width 0.1)
				(type default)
			)
			(layer "B.Fab")
		)
		(fp_line
			(start 0.8636 0.4572)
			(end 0.8636 0.4064)
			(stroke
				(width 0.1)
				(type default)
			)
			(layer "B.Fab")
		)
		(fp_line
			(start -1.1938 0.4064)
			(end -0.8636 0.4064)
			(stroke
				(width 0.1)
				(type default)
			)
			(layer "B.Fab")
		)
		(fp_line
			(start -0.8636 0.4064)
			(end -0.8636 0.4572)
			(stroke
				(width 0.1)
				(type default)
			)
			(layer "B.Fab")
		)
		(fp_line
			(start 0.8636 0.4064)
			(end 1.1938 0.4064)
			(stroke
				(width 0.1)
				(type default)
			)
			(layer "B.Fab")
		)
		(fp_line
			(start 1.1938 0.4064)
			(end 1.1938 -0.4064)
			(stroke
				(width 0.1)
				(type default)
			)
			(layer "B.Fab")
		)
		(fp_line
			(start -1.1938 -0.4064)
			(end -1.1938 0.4064)
			(stroke
				(width 0.1)
				(type default)
			)
			(layer "B.Fab")
		)
		(fp_line
			(start -0.8636 -0.4064)
			(end -1.1938 -0.4064)
			(stroke
				(width 0.1)
				(type default)
			)
			(layer "B.Fab")
		)
		(fp_line
			(start 0.8636 -0.4064)
			(end 0.8636 -0.4572)
			(stroke
				(width 0.1)
				(type default)
			)
			(layer "B.Fab")
		)
		(fp_line
			(start 1.1938 -0.4064)
			(end 0.8636 -0.4064)
			(stroke
				(width 0.1)
				(type default)
			)
			(layer "B.Fab")
		)
		(fp_line
			(start -0.8636 -0.4572)
			(end -0.8636 -0.4064)
			(stroke
				(width 0.1)
				(type default)
			)
			(layer "B.Fab")
		)
		(fp_line
			(start 0.8636 -0.4572)
			(end -0.8636 -0.4572)
			(stroke
				(width 0.1)
				(type default)
			)
			(layer "B.Fab")
		)
		(pad "1" smd rect
			(at 0.7366 0 180)
			(size 0.7112 0.8128)
			(layers "B.Cu" "B.Mask" "B.Paste")
			(net "P1V25_PEX2")
		)
		(pad "2" smd rect
			(at -0.7366 0 180)
			(size 0.7112 0.8128)
			(layers "B.Cu" "B.Mask" "B.Paste")
			(net "GND")
		)
	)
	(footprint ""
		(layer "B.Cu")
		(at 416.051238 -305.399948 -90)
		(property "Reference" "C3494"
			(at 0 0 90)
			(layer "B.SilkS")
			(hide yes)
			(effects
				(font
					(size 1.27 1.27)
				)
				(justify mirror)
			)
		)
		(property "Value" ""
			(at 0 0 90)
			(layer "B.Fab")
			(effects
				(font
					(size 1.27 1.27)
				)
				(justify mirror)
			)
		)
		(duplicate_pad_numbers_are_jumpers no)
		(fp_line
			(start -0.299974 0.150114)
			(end 0.299974 0.150114)
			(stroke
				(width 0.1)
				(type default)
			)
			(layer "B.Fab")
		)
		(fp_line
			(start 0.299974 0.150114)
			(end 0.299974 -0.150114)
			(stroke
				(width 0.1)
				(type default)
			)
			(layer "B.Fab")
		)
		(fp_line
			(start -0.299974 -0.150114)
			(end -0.299974 0.150114)
			(stroke
				(width 0.1)
				(type default)
			)
			(layer "B.Fab")
		)
		(fp_line
			(start 0.299974 -0.150114)
			(end -0.299974 -0.150114)
			(stroke
				(width 0.1)
				(type default)
			)
			(layer "B.Fab")
		)
		(pad "1" smd rect
			(at 0.2667 0 90)
			(size 0.3048 0.381)
			(layers "B.Cu" "B.Mask" "B.Paste")
			(net "P1V25_SERDES_VDDPLL_PEX3")
		)
		(pad "2" smd rect
			(at -0.2667 0 90)
			(size 0.3048 0.381)
			(layers "B.Cu" "B.Mask" "B.Paste")
			(net "GND")
		)
	)
	(footprint ""
		(layer "B.Cu")
		(at 284.249876 -288.299906 90)
		(property "Reference" "C3279"
			(at 0 0 90)
			(layer "B.SilkS")
			(hide yes)
			(effects
				(font
					(size 1.27 1.27)
				)
				(justify mirror)
			)
		)
		(property "Value" ""
			(at 0 0 90)
			(layer "B.Fab")
			(effects
				(font
					(size 1.27 1.27)
				)
				(justify mirror)
			)
		)
		(duplicate_pad_numbers_are_jumpers no)
		(fp_line
			(start 0.299974 -0.150114)
			(end -0.299974 -0.150114)
			(stroke
				(width 0.1)
				(type default)
			)
			(layer "B.Fab")
		)
		(fp_line
			(start -0.299974 -0.150114)
			(end -0.299974 0.150114)
			(stroke
				(width 0.1)
				(type default)
			)
			(layer "B.Fab")
		)
		(fp_line
			(start 0.299974 0.150114)
			(end 0.299974 -0.150114)
			(stroke
				(width 0.1)
				(type default)
			)
			(layer "B.Fab")
		)
		(fp_line
			(start -0.299974 0.150114)
			(end 0.299974 0.150114)
			(stroke
				(width 0.1)
				(type default)
			)
			(layer "B.Fab")
		)
		(pad "1" smd rect
			(at 0.2667 0 270)
			(size 0.3048 0.381)
			(layers "B.Cu" "B.Mask" "B.Paste")
			(net "P1V25_PEX2")
		)
		(pad "2" smd rect
			(at -0.2667 0 270)
			(size 0.3048 0.381)
			(layers "B.Cu" "B.Mask" "B.Paste")
			(net "GND")
		)
	)
	(footprint ""
		(layer "B.Cu")
		(at 177.649886 -288.299906 90)
		(property "Reference" "C3105"
			(at 0 0 90)
			(layer "B.SilkS")
			(hide yes)
			(effects
				(font
					(size 1.27 1.27)
				)
				(justify mirror)
			)
		)
		(property "Value" ""
			(at 0 0 90)
			(layer "B.Fab")
			(effects
				(font
					(size 1.27 1.27)
				)
				(justify mirror)
			)
		)
		(duplicate_pad_numbers_are_jumpers no)
		(fp_line
			(start 0.299974 -0.150114)
			(end -0.299974 -0.150114)
			(stroke
				(width 0.1)
				(type default)
			)
			(layer "B.Fab")
		)
		(fp_line
			(start -0.299974 -0.150114)
			(end -0.299974 0.150114)
			(stroke
				(width 0.1)
				(type default)
			)
			(layer "B.Fab")
		)
		(fp_line
			(start 0.299974 0.150114)
			(end 0.299974 -0.150114)
			(stroke
				(width 0.1)
				(type default)
			)
			(layer "B.Fab")
		)
		(fp_line
			(start -0.299974 0.150114)
			(end 0.299974 0.150114)
			(stroke
				(width 0.1)
				(type default)
			)
			(layer "B.Fab")
		)
		(pad "1" smd rect
			(at 0.2667 0 270)
			(size 0.3048 0.381)
			(layers "B.Cu" "B.Mask" "B.Paste")
			(net "P1V25_PEX1")
		)
		(pad "2" smd rect
			(at -0.2667 0 270)
			(size 0.3048 0.381)
			(layers "B.Cu" "B.Mask" "B.Paste")
			(net "GND")
		)
	)
	(footprint ""
		(layer "B.Cu")
		(at 354.862384 -308.613556 90)
		(property "Reference" "C1925"
			(at 0 0 90)
			(layer "B.SilkS")
			(hide yes)
			(effects
				(font
					(size 1.27 1.27)
				)
				(justify mirror)
			)
		)
		(property "Value" ""
			(at 0 0 90)
			(layer "B.Fab")
			(effects
				(font
					(size 1.27 1.27)
				)
				(justify mirror)
			)
		)
		(duplicate_pad_numbers_are_jumpers no)
		(fp_line
			(start 1.2954 -0.5842)
			(end -1.2954 -0.5842)
			(stroke
				(width 0.1524)
				(type default)
			)
			(layer "B.SilkS")
		)
		(fp_line
			(start -1.2954 -0.5842)
			(end -1.2954 0.5842)
			(stroke
				(width 0.1524)
				(type default)
			)
			(layer "B.SilkS")
		)
		(fp_line
			(start 1.2954 0.5842)
			(end 1.2954 -0.5842)
			(stroke
				(width 0.1524)
				(type default)
			)
			(layer "B.SilkS")
		)
		(fp_line
			(start -1.2954 0.5842)
			(end 1.2954 0.5842)
			(stroke
				(width 0.1524)
				(type default)
			)
			(layer "B.SilkS")
		)
		(fp_line
			(start 0.8636 -0.4572)
			(end -0.8636 -0.4572)
			(stroke
				(width 0.1)
				(type default)
			)
			(layer "B.Fab")
		)
		(fp_line
			(start -0.8636 -0.4572)
			(end -0.8636 -0.4064)
			(stroke
				(width 0.1)
				(type default)
			)
			(layer "B.Fab")
		)
		(fp_line
			(start 1.1938 -0.4064)
			(end 0.8636 -0.4064)
			(stroke
				(width 0.1)
				(type default)
			)
			(layer "B.Fab")
		)
		(fp_line
			(start 0.8636 -0.4064)
			(end 0.8636 -0.4572)
			(stroke
				(width 0.1)
				(type default)
			)
			(layer "B.Fab")
		)
		(fp_line
			(start -0.8636 -0.4064)
			(end -1.1938 -0.4064)
			(stroke
				(width 0.1)
				(type default)
			)
			(layer "B.Fab")
		)
		(fp_line
			(start -1.1938 -0.4064)
			(end -1.1938 0.4064)
			(stroke
				(width 0.1)
				(type default)
			)
			(layer "B.Fab")
		)
		(fp_line
			(start 1.1938 0.4064)
			(end 1.1938 -0.4064)
			(stroke
				(width 0.1)
				(type default)
			)
			(layer "B.Fab")
		)
		(fp_line
			(start 0.8636 0.4064)
			(end 1.1938 0.4064)
			(stroke
				(width 0.1)
				(type default)
			)
			(layer "B.Fab")
		)
		(fp_line
			(start -0.8636 0.4064)
			(end -0.8636 0.4572)
			(stroke
				(width 0.1)
				(type default)
			)
			(layer "B.Fab")
		)
		(fp_line
			(start -1.1938 0.4064)
			(end -0.8636 0.4064)
			(stroke
				(width 0.1)
				(type default)
			)
			(layer "B.Fab")
		)
		(fp_line
			(start 0.8636 0.4572)
			(end 0.8636 0.4064)
			(stroke
				(width 0.1)
				(type default)
			)
			(layer "B.Fab")
		)
		(fp_line
			(start -0.8636 0.4572)
			(end 0.8636 0.4572)
			(stroke
				(width 0.1)
				(type default)
			)
			(layer "B.Fab")
		)
		(pad "1" smd rect
			(at 0.7366 0)
			(size 0.7112 0.8128)
			(layers "B.Cu" "B.Mask" "B.Paste")
			(net "P0V8_SERDES_VDDA_PEX3")
		)
		(pad "2" smd rect
			(at -0.7366 0)
			(size 0.7112 0.8128)
			(layers "B.Cu" "B.Mask" "B.Paste")
			(net "GND")
		)
	)
	(footprint ""
		(layer "B.Cu")
		(at 411.675326 -109.481366 180)
		(property "Reference" "R389"
			(at 0 0 0)
			(layer "B.SilkS")
			(hide yes)
			(effects
				(font
					(size 1.27 1.27)
				)
				(justify mirror)
			)
		)
		(property "Value" ""
			(at 0 0 0)
			(layer "B.Fab")
			(effects
				(font
					(size 1.27 1.27)
				)
				(justify mirror)
			)
		)
		(duplicate_pad_numbers_are_jumpers no)
		(fp_line
			(start 0.7874 0.4064)
			(end 0.7874 -0.4064)
			(stroke
				(width 0.1524)
				(type default)
			)
			(layer "B.SilkS")
		)
		(fp_line
			(start 0.7874 -0.4064)
			(end -0.7874 -0.4064)
			(stroke
				(width 0.1524)
				(type default)
			)
			(layer "B.SilkS")
		)
		(fp_line
			(start -0.7874 0.4064)
			(end 0.7874 0.4064)
			(stroke
				(width 0.1524)
				(type default)
			)
			(layer "B.SilkS")
		)
		(fp_line
			(start -0.7874 -0.4064)
			(end -0.7874 0.4064)
			(stroke
				(width 0.1524)
				(type default)
			)
			(layer "B.SilkS")
		)
		(fp_line
			(start 0.67945 0.3048)
			(end 0.67945 -0.305054)
			(stroke
				(width 0.1)
				(type default)
			)
			(layer "B.Fab")
		)
		(fp_line
			(start 0.67945 -0.305054)
			(end 0.12065 -0.305054)
			(stroke
				(width 0.1)
				(type default)
			)
			(layer "B.Fab")
		)
		(fp_line
			(start 0.12065 0.3048)
			(end 0.67945 0.3048)
			(stroke
				(width 0.1)
				(type default)
			)
			(layer "B.Fab")
		)
		(fp_line
			(start 0.12065 0.2794)
			(end 0.12065 0.3048)
			(stroke
				(width 0.1)
				(type default)
			)
			(layer "B.Fab")
		)
		(fp_line
			(start 0.12065 -0.2794)
			(end -0.12065 -0.2794)
			(stroke
				(width 0.1)
				(type default)
			)
			(layer "B.Fab")
		)
		(fp_line
			(start 0.12065 -0.305054)
			(end 0.12065 -0.2794)
			(stroke
				(width 0.1)
				(type default)
			)
			(layer "B.Fab")
		)
		(fp_line
			(start -0.120396 0.3048)
			(end -0.120396 0.2794)
			(stroke
				(width 0.1)
				(type default)
			)
			(layer "B.Fab")
		)
		(fp_line
			(start -0.120396 0.2794)
			(end 0.12065 0.2794)
			(stroke
				(width 0.1)
				(type default)
			)
			(layer "B.Fab")
		)
		(fp_line
			(start -0.12065 -0.2794)
			(end -0.12065 -0.3048)
			(stroke
				(width 0.1)
				(type default)
			)
			(layer "B.Fab")
		)
		(fp_line
			(start -0.12065 -0.3048)
			(end -0.67945 -0.3048)
			(stroke
				(width 0.1)
				(type default)
			)
			(layer "B.Fab")
		)
		(fp_line
			(start -0.67945 0.3048)
			(end -0.120396 0.3048)
			(stroke
				(width 0.1)
				(type default)
			)
			(layer "B.Fab")
		)
		(fp_line
			(start -0.67945 -0.3048)
			(end -0.67945 0.3048)
			(stroke
				(width 0.1)
				(type default)
			)
			(layer "B.Fab")
		)
		(pad "1" smd circle
			(at 0.40005 0)
			(size 0 0)
			(layers "B.Cu" "B.Mask" "B.Paste")
			(net "NIC7_BIF1_N")
		)
		(pad "2" smd circle
			(at -0.40005 0)
			(size 0 0)
			(layers "B.Cu" "B.Mask" "B.Paste")
			(net "GND")
		)
	)
)
